(kicad_pcb
	(version 20260206)
	(generator "pcbnew")
	(generator_version "10.0")
	(general
		(thickness 1.6)
		(legacy_teardrops no)
	)
	(paper "A4")
	(title_block
		(title "Wiwynn_Tioga_Pass_MB.brd")
		(comment 1 "Tioga Pass / footprints 2328-2335 of 4770")
	)
	(layers
		(0 "F.Cu" signal "TOP")
		(4 "In1.Cu" signal "L2GND")
		(6 "In2.Cu" signal "L3")
		(8 "In3.Cu" signal "L4GND")
		(10 "In4.Cu" signal "L5")
		(12 "In5.Cu" signal "L6GND")
		(14 "In6.Cu" signal "L7VCC")
		(16 "In7.Cu" signal "L8VCC")
		(18 "In8.Cu" signal "L9GND")
		(20 "In9.Cu" signal "L10")
		(22 "In10.Cu" signal "L11GND")
		(24 "In11.Cu" signal "L12")
		(26 "In12.Cu" signal "L13GND")
		(2 "B.Cu" signal "BOTTOM")
		(9 "F.Adhes" user "F.Adhesive")
		(11 "B.Adhes" user "B.Adhesive")
		(13 "F.Paste" user "Package Geometry/Pastemask Top")
		(15 "B.Paste" user "Package Geometry/Pastemask Bottom")
		(5 "F.SilkS" user "Ref Des/Silkscreen Top")
		(7 "B.SilkS" user "Ref Des/Silkscreen Bottom")
		(1 "F.Mask" user "Board Geometry/Soldermask Top")
		(3 "B.Mask" user "Board Geometry/Soldermask Bottom")
		(17 "Dwgs.User" user "User.Drawings")
		(19 "Cmts.User" user "User.Comments")
		(21 "Eco1.User" user "User.Eco1")
		(23 "Eco2.User" user "User.Eco2")
		(25 "Edge.Cuts" user "Board Geometry/Outline")
		(27 "Margin" user)
		(31 "F.CrtYd" user "Package Geometry/Place Bound Top")
		(29 "B.CrtYd" user "Package Geometry/Place Bound Bottom")
		(35 "F.Fab" user "Ref Des/Assembly Top")
		(33 "B.Fab" user "Ref Des/Assembly Bottom")
	)
	(footprint ""
		(layer "F.Cu")
		(at 25.035002 -88.130634 180)
		(property "Reference" "CF8"
			(at 0 0 180)
			(layer "F.SilkS")
			(hide yes)
			(effects
				(font
					(size 1.27 1.27)
				)
			)
		)
		(property "Value" "*"
			(at 1.1811 -2.8194 180)
			(unlocked yes)
			(layer "F.Fab")
			(hide yes)
			(effects
				(font
					(size 1.27 1.016)
					(thickness 0.1524)
				)
			)
		)
		(property "Device Type" "SC22P50V2JN-4GP_SMD-BCG-SC22P5A"
			(at 1.1811 -4.3434 180)
			(unlocked yes)
			(layer "F.Fab")
			(hide yes)
			(effects
				(font
					(size 1.27 1.016)
					(thickness 0.1524)
				)
			)
		)
		(duplicate_pad_numbers_are_jumpers no)
		(fp_rect
			(start -0.4318 0.9525)
			(end 0.4318 -0.9525)
			(stroke
				(width 0)
				(type default)
			)
			(fill no)
			(layer "F.CrtYd")
		)
		(fp_rect
			(start -0.4318 0.9525)
			(end 0.4318 -0.9525)
			(stroke
				(width 0)
				(type default)
			)
			(fill no)
			(layer "F.Fab")
		)
		(pad "1" smd custom
			(at 0 -0.4445 180)
			(size 0.1524 0.1524)
			(layers "F.Cu" "F.Mask" "F.Paste")
			(net "VR_PVCCIN_CPU1_AIREF2")
			(options
				(clearance outline)
				(anchor circle)
			)
			(primitives
				(gr_poly
					(pts
						(arc
							(start 0.3048 -0.2032)
							(mid 0.275042 -0.275042)
							(end 0.2032 -0.3048)
						)
						(arc
							(start -0.2032 -0.3048)
							(mid -0.275042 -0.275042)
							(end -0.3048 -0.2032)
						)
						(arc
							(start -0.3048 0.2032)
							(mid -0.275042 0.275042)
							(end -0.2032 0.3048)
						)
						(arc
							(start 0.2032 0.3048)
							(mid 0.275042 0.275042)
							(end 0.3048 0.2032)
						)
					)
					(width 0)
					(fill yes)
				)
			)
		)
		(pad "2" smd custom
			(at 0 0.4445 180)
			(size 0.1524 0.1524)
			(layers "F.Cu" "F.Mask" "F.Paste")
			(net "ISENSE_PVCCIN_CPU1_PH2_IMON")
			(options
				(clearance outline)
				(anchor circle)
			)
			(primitives
				(gr_poly
					(pts
						(arc
							(start 0.3048 -0.2032)
							(mid 0.275042 -0.275042)
							(end 0.2032 -0.3048)
						)
						(arc
							(start -0.2032 -0.3048)
							(mid -0.275042 -0.275042)
							(end -0.3048 -0.2032)
						)
						(arc
							(start -0.3048 0.2032)
							(mid -0.275042 0.275042)
							(end -0.2032 0.3048)
						)
						(arc
							(start 0.2032 0.3048)
							(mid 0.275042 0.275042)
							(end 0.3048 0.2032)
						)
					)
					(width 0)
					(fill yes)
				)
			)
		)
	)
	(footprint ""
		(layer "F.Cu")
		(at 388.992618 -156.591 90)
		(property "Reference" "C7A9"
			(at 0 0 90)
			(layer "F.SilkS")
			(hide yes)
			(effects
				(font
					(size 1.27 1.27)
				)
			)
		)
		(property "Value" ""
			(at 0 0 90)
			(layer "F.Fab")
			(effects
				(font
					(size 1.27 1.27)
				)
			)
		)
		(duplicate_pad_numbers_are_jumpers no)
		(fp_poly
			(pts
				(xy 0.3048 -0.1016) (xy 0.3048 0.9906) (xy -0.3048 0.9906) (xy -0.3048 -0.1016)
			)
			(stroke
				(width 0)
				(type default)
			)
			(fill no)
			(layer "F.CrtYd")
		)
		(fp_line
			(start 0.3048 -0.1016)
			(end -0.3048 -0.1016)
			(stroke
				(width 0.1)
				(type default)
			)
			(layer "F.Fab")
		)
		(fp_line
			(start -0.3048 -0.1016)
			(end -0.3048 0.9906)
			(stroke
				(width 0.1)
				(type default)
			)
			(layer "F.Fab")
		)
		(fp_line
			(start 0.3048 0.9906)
			(end 0.3048 -0.1016)
			(stroke
				(width 0.1)
				(type default)
			)
			(layer "F.Fab")
		)
		(fp_line
			(start -0.3048 0.9906)
			(end 0.3048 0.9906)
			(stroke
				(width 0.1)
				(type default)
			)
			(layer "F.Fab")
		)
		(pad "1" smd rect
			(at 0 0 90)
			(size 0.508 0.508)
			(layers "F.Cu" "F.Mask" "F.Paste")
			(net "VR_FET_SW_P12V_STBY_PVDDQ_DEF")
		)
		(pad "2" smd rect
			(at 0 0.889 90)
			(size 0.508 0.508)
			(layers "F.Cu" "F.Mask" "F.Paste")
			(net "GND")
		)
		(zone
			(layer "F.Cu")
			(hatch none 0.5)
			(connect_pads
				(clearance 0)
			)
			(min_thickness 0.25)
			(keepout
				(tracks allowed)
				(vias not_allowed)
				(pads allowed)
				(copperpour not_allowed)
				(footprints allowed)
			)
			(placement
				(enabled no)
				(sheetname "")
			)
			(fill
				(thermal_gap 0.5)
				(thermal_bridge_width 0.5)
				(island_removal_mode 0)
			)
			(polygon
				(pts
					(xy 389.246618 -156.337) (xy 389.246618 -156.845) (xy 389.627618 -156.845) (xy 389.627618 -156.337)
				)
			)
		)
		(zone
			(layer "F.Cu")
			(hatch none 0.5)
			(connect_pads
				(clearance 0)
			)
			(min_thickness 0.25)
			(keepout
				(tracks not_allowed)
				(vias allowed)
				(pads allowed)
				(copperpour not_allowed)
				(footprints allowed)
			)
			(placement
				(enabled no)
				(sheetname "")
			)
			(fill
				(thermal_gap 0.5)
				(thermal_bridge_width 0.5)
				(island_removal_mode 0)
			)
			(polygon
				(pts
					(xy 389.627618 -156.337) (xy 389.627618 -156.845) (xy 389.246618 -156.845) (xy 389.246618 -156.337)
				)
			)
		)
	)
	(footprint ""
		(layer "F.Cu")
		(at 375.158 -88.2015)
		(property "Reference" "R7C15"
			(at 0 0 0)
			(layer "F.SilkS")
			(hide yes)
			(effects
				(font
					(size 1.27 1.27)
				)
			)
		)
		(property "Value" ""
			(at 0 0 0)
			(layer "F.Fab")
			(effects
				(font
					(size 1.27 1.27)
				)
			)
		)
		(duplicate_pad_numbers_are_jumpers no)
		(fp_rect
			(start -0.2794 -0.1016)
			(end 0.2794 0.9906)
			(stroke
				(width 0)
				(type default)
			)
			(fill no)
			(layer "F.CrtYd")
		)
		(fp_line
			(start -0.2794 -0.1016)
			(end -0.2794 0.9906)
			(stroke
				(width 0.1)
				(type default)
			)
			(layer "F.Fab")
		)
		(fp_line
			(start -0.2794 0.9906)
			(end 0.2794 0.9906)
			(stroke
				(width 0.1)
				(type default)
			)
			(layer "F.Fab")
		)
		(fp_line
			(start 0.2794 -0.1016)
			(end -0.2794 -0.1016)
			(stroke
				(width 0.1)
				(type default)
			)
			(layer "F.Fab")
		)
		(fp_line
			(start 0.2794 0.9906)
			(end 0.2794 -0.1016)
			(stroke
				(width 0.1)
				(type default)
			)
			(layer "F.Fab")
		)
		(pad "1" smd rect
			(at 0 0)
			(size 0.508 0.508)
			(layers "F.Cu" "F.Mask" "F.Paste")
			(net "SPI_PCH_MOSI_R")
		)
		(pad "2" smd rect
			(at 0 0.889)
			(size 0.508 0.508)
			(layers "F.Cu" "F.Mask" "F.Paste")
			(net "SPI_PCH_MOSI")
		)
		(zone
			(layer "F.Cu")
			(hatch none 0.5)
			(connect_pads
				(clearance 0)
			)
			(min_thickness 0.25)
			(keepout
				(tracks allowed)
				(vias not_allowed)
				(pads allowed)
				(copperpour not_allowed)
				(footprints allowed)
			)
			(placement
				(enabled no)
				(sheetname "")
			)
			(fill
				(thermal_gap 0.5)
				(thermal_bridge_width 0.5)
				(island_removal_mode 0)
			)
			(polygon
				(pts
					(xy 374.904 -87.9475) (xy 374.904 -87.5665) (xy 375.412 -87.5665) (xy 375.412 -87.9475)
				)
			)
		)
		(zone
			(layer "F.Cu")
			(hatch none 0.5)
			(connect_pads
				(clearance 0)
			)
			(min_thickness 0.25)
			(keepout
				(tracks not_allowed)
				(vias allowed)
				(pads allowed)
				(copperpour not_allowed)
				(footprints allowed)
			)
			(placement
				(enabled no)
				(sheetname "")
			)
			(fill
				(thermal_gap 0.5)
				(thermal_bridge_width 0.5)
				(island_removal_mode 0)
			)
			(polygon
				(pts
					(xy 374.904 -87.9475) (xy 374.904 -87.5665) (xy 375.412 -87.5665) (xy 375.412 -87.9475)
				)
			)
		)
	)
	(footprint ""
		(layer "F.Cu")
		(at 405.283416 -150.468584 90)
		(property "Reference" "C8A10"
			(at 0 0 90)
			(layer "F.SilkS")
			(hide yes)
			(effects
				(font
					(size 1.27 1.27)
				)
			)
		)
		(property "Value" ""
			(at 0 0 90)
			(layer "F.Fab")
			(effects
				(font
					(size 1.27 1.27)
				)
			)
		)
		(duplicate_pad_numbers_are_jumpers no)
		(fp_poly
			(pts
				(xy 0.3048 -0.1016) (xy 0.3048 0.9906) (xy -0.3048 0.9906) (xy -0.3048 -0.1016)
			)
			(stroke
				(width 0)
				(type default)
			)
			(fill no)
			(layer "F.CrtYd")
		)
		(fp_line
			(start 0.3048 -0.1016)
			(end -0.3048 -0.1016)
			(stroke
				(width 0.1)
				(type default)
			)
			(layer "F.Fab")
		)
		(fp_line
			(start -0.3048 -0.1016)
			(end -0.3048 0.9906)
			(stroke
				(width 0.1)
				(type default)
			)
			(layer "F.Fab")
		)
		(fp_line
			(start 0.3048 0.9906)
			(end 0.3048 -0.1016)
			(stroke
				(width 0.1)
				(type default)
			)
			(layer "F.Fab")
		)
		(fp_line
			(start -0.3048 0.9906)
			(end 0.3048 0.9906)
			(stroke
				(width 0.1)
				(type default)
			)
			(layer "F.Fab")
		)
		(pad "1" smd rect
			(at 0 0 90)
			(size 0.508 0.508)
			(layers "F.Cu" "F.Mask" "F.Paste")
			(net "PWRGD_P3V3_STBY")
		)
		(pad "2" smd rect
			(at 0 0.889 90)
			(size 0.508 0.508)
			(layers "F.Cu" "F.Mask" "F.Paste")
			(net "GND")
		)
		(zone
			(layer "F.Cu")
			(hatch none 0.5)
			(connect_pads
				(clearance 0)
			)
			(min_thickness 0.25)
			(keepout
				(tracks allowed)
				(vias not_allowed)
				(pads allowed)
				(copperpour not_allowed)
				(footprints allowed)
			)
			(placement
				(enabled no)
				(sheetname "")
			)
			(fill
				(thermal_gap 0.5)
				(thermal_bridge_width 0.5)
				(island_removal_mode 0)
			)
			(polygon
				(pts
					(xy 405.537416 -150.214584) (xy 405.537416 -150.722584) (xy 405.918416 -150.722584) (xy 405.918416 -150.214584)
				)
			)
		)
		(zone
			(layer "F.Cu")
			(hatch none 0.5)
			(connect_pads
				(clearance 0)
			)
			(min_thickness 0.25)
			(keepout
				(tracks not_allowed)
				(vias allowed)
				(pads allowed)
				(copperpour not_allowed)
				(footprints allowed)
			)
			(placement
				(enabled no)
				(sheetname "")
			)
			(fill
				(thermal_gap 0.5)
				(thermal_bridge_width 0.5)
				(island_removal_mode 0)
			)
			(polygon
				(pts
					(xy 405.918416 -150.214584) (xy 405.918416 -150.722584) (xy 405.537416 -150.722584) (xy 405.537416 -150.214584)
				)
			)
		)
	)
	(footprint ""
		(layer "F.Cu")
		(at 263.186672 -73.318116)
		(property "Reference" "C5D43"
			(at 0 0 0)
			(layer "F.SilkS")
			(hide yes)
			(effects
				(font
					(size 1.27 1.27)
				)
			)
		)
		(property "Value" ""
			(at 0 0 0)
			(layer "F.Fab")
			(effects
				(font
					(size 1.27 1.27)
				)
			)
		)
		(duplicate_pad_numbers_are_jumpers no)
		(fp_poly
			(pts
				(xy -0.4953 -0.2032) (xy 0.4953 -0.2032) (xy 0.4953 1.6002) (xy -0.4953 1.6002)
			)
			(stroke
				(width 0)
				(type default)
			)
			(fill no)
			(layer "F.CrtYd")
		)
		(fp_line
			(start -0.4953 -0.2032)
			(end 0.4953 -0.2032)
			(stroke
				(width 0.1)
				(type default)
			)
			(layer "F.Fab")
		)
		(fp_line
			(start -0.4953 1.6002)
			(end -0.4953 -0.2032)
			(stroke
				(width 0.1)
				(type default)
			)
			(layer "F.Fab")
		)
		(fp_line
			(start 0.4953 -0.2032)
			(end 0.4953 1.6002)
			(stroke
				(width 0.1)
				(type default)
			)
			(layer "F.Fab")
		)
		(fp_line
			(start 0.4953 1.6002)
			(end -0.4953 1.6002)
			(stroke
				(width 0.1)
				(type default)
			)
			(layer "F.Fab")
		)
		(pad "1" smd rect
			(at 0 0)
			(size 0.762 0.889)
			(layers "F.Cu" "F.Mask" "F.Paste")
			(net "PVCCIN_CPU0")
		)
		(pad "2" smd rect
			(at 0 1.397)
			(size 0.762 0.889)
			(layers "F.Cu" "F.Mask" "F.Paste")
			(net "GND")
		)
		(zone
			(layer "F.Cu")
			(hatch none 0.5)
			(connect_pads
				(clearance 0)
			)
			(min_thickness 0.25)
			(keepout
				(tracks not_allowed)
				(vias allowed)
				(pads allowed)
				(copperpour not_allowed)
				(footprints allowed)
			)
			(placement
				(enabled no)
				(sheetname "")
			)
			(fill
				(thermal_gap 0.5)
				(thermal_bridge_width 0.5)
				(island_removal_mode 0)
			)
			(polygon
				(pts
					(xy 262.805672 -72.873616) (xy 263.567672 -72.873616) (xy 263.567672 -72.365616) (xy 262.805672 -72.365616)
				)
			)
		)
	)
	(footprint ""
		(layer "F.Cu")
		(at 166.271448 -10.0711 90)
		(property "Reference" "R4G6"
			(at 0 0 90)
			(layer "F.SilkS")
			(hide yes)
			(effects
				(font
					(size 1.27 1.27)
				)
			)
		)
		(property "Value" ""
			(at 0 0 90)
			(layer "F.Fab")
			(effects
				(font
					(size 1.27 1.27)
				)
			)
		)
		(duplicate_pad_numbers_are_jumpers no)
		(fp_poly
			(pts
				(xy -0.4953 -0.2032) (xy 0.4953 -0.2032) (xy 0.4953 1.6002) (xy -0.4953 1.6002)
			)
			(stroke
				(width 0)
				(type default)
			)
			(fill no)
			(layer "F.CrtYd")
		)
		(fp_line
			(start 0.4953 -0.2032)
			(end 0.4953 1.6002)
			(stroke
				(width 0.1)
				(type default)
			)
			(layer "F.Fab")
		)
		(fp_line
			(start -0.4953 -0.2032)
			(end 0.4953 -0.2032)
			(stroke
				(width 0.1)
				(type default)
			)
			(layer "F.Fab")
		)
		(fp_line
			(start 0.4953 1.6002)
			(end -0.4953 1.6002)
			(stroke
				(width 0.1)
				(type default)
			)
			(layer "F.Fab")
		)
		(fp_line
			(start -0.4953 1.6002)
			(end -0.4953 -0.2032)
			(stroke
				(width 0.1)
				(type default)
			)
			(layer "F.Fab")
		)
		(pad "1" smd rect
			(at 0 0 90)
			(size 0.762 0.889)
			(layers "F.Cu" "F.Mask" "F.Paste")
			(net "PVPP_GHJ")
		)
		(pad "2" smd rect
			(at 0 1.397 90)
			(size 0.762 0.889)
			(layers "F.Cu" "F.Mask" "F.Paste")
			(net "GND")
		)
		(zone
			(layer "F.Cu")
			(hatch none 0.5)
			(connect_pads
				(clearance 0)
			)
			(min_thickness 0.25)
			(keepout
				(tracks allowed)
				(vias not_allowed)
				(pads allowed)
				(copperpour not_allowed)
				(footprints allowed)
			)
			(placement
				(enabled no)
				(sheetname "")
			)
			(fill
				(thermal_gap 0.5)
				(thermal_bridge_width 0.5)
				(island_removal_mode 0)
			)
			(polygon
				(pts
					(xy 167.223948 -10.4521) (xy 166.715948 -10.4521) (xy 166.715948 -9.6901) (xy 167.223948 -9.6901)
				)
			)
		)
		(zone
			(layer "F.Cu")
			(hatch none 0.5)
			(connect_pads
				(clearance 0)
			)
			(min_thickness 0.25)
			(keepout
				(tracks not_allowed)
				(vias allowed)
				(pads allowed)
				(copperpour not_allowed)
				(footprints allowed)
			)
			(placement
				(enabled no)
				(sheetname "")
			)
			(fill
				(thermal_gap 0.5)
				(thermal_bridge_width 0.5)
				(island_removal_mode 0)
			)
			(polygon
				(pts
					(xy 167.223948 -9.6901) (xy 167.223948 -10.4521) (xy 166.715948 -10.4521) (xy 166.715948 -9.6901)
				)
			)
		)
	)
	(footprint ""
		(layer "B.Cu")
		(at 488.244896 -55.856378)
		(property "Reference" "C30W8"
			(at 0 0 0)
			(layer "B.SilkS")
			(hide yes)
			(effects
				(font
					(size 1.27 1.27)
				)
				(justify mirror)
			)
		)
		(property "Value" "*"
			(at 0.0762 -6.2357 0)
			(unlocked yes)
			(layer "B.Fab")
			(hide yes)
			(effects
				(font
					(size 1.27 1.016)
					(thickness 0.1524)
				)
				(justify mirror)
			)
		)
		(property "Device Type" "SC22U16V5MX-4-GP_SMD-BCG5-SC22A"
			(at 0.0762 -8.2677 0)
			(unlocked yes)
			(layer "B.Fab")
			(hide yes)
			(effects
				(font
					(size 1.27 1.016)
					(thickness 0.1524)
				)
				(justify mirror)
			)
		)
		(duplicate_pad_numbers_are_jumpers no)
		(fp_line
			(start -0.635 0)
			(end 0.635 0)
			(stroke
				(width 0.508)
				(type default)
			)
			(layer "B.SilkS")
		)
		(fp_rect
			(start 0.9652 1.778)
			(end -0.9652 -1.778)
			(stroke
				(width 0)
				(type default)
			)
			(fill no)
			(layer "B.CrtYd")
		)
		(fp_poly
			(pts
				(xy 0.9652 -1.778) (xy -0.9652 -1.778) (xy -0.9652 1.778) (xy 0.9652 1.778)
			)
			(stroke
				(width 0)
				(type default)
			)
			(fill no)
			(layer "B.Fab")
		)
		(pad "1" smd rect
			(at 0 -0.9652 180)
			(size 1.397 1.143)
			(layers "B.Cu" "B.Mask" "B.Paste")
			(net "P5V_STBY_USBC")
		)
		(pad "2" smd rect
			(at 0 0.9652 180)
			(size 1.397 1.143)
			(layers "B.Cu" "B.Mask" "B.Paste")
			(net "GND")
		)
	)
	(footprint ""
		(layer "B.Cu")
		(at 406.892506 -32.6644 -90)
		(property "Reference" "R1T26"
			(at 0 0 90)
			(layer "B.SilkS")
			(hide yes)
			(effects
				(font
					(size 1.27 1.27)
				)
				(justify mirror)
			)
		)
		(property "Value" ""
			(at 0 0 90)
			(layer "B.Fab")
			(effects
				(font
					(size 1.27 1.27)
				)
				(justify mirror)
			)
		)
		(duplicate_pad_numbers_are_jumpers no)
		(fp_poly
			(pts
				(xy 0.2794 -0.1016) (xy -0.2794 -0.1016) (xy -0.2794 0.9906) (xy 0.2794 0.9906)
			)
			(stroke
				(width 0)
				(type default)
			)
			(fill no)
			(layer "B.CrtYd")
		)
		(fp_line
			(start -0.2794 0.9906)
			(end -0.2794 -0.1016)
			(stroke
				(width 0.1)
				(type default)
			)
			(layer "B.Fab")
		)
		(fp_line
			(start 0.2794 0.9906)
			(end -0.2794 0.9906)
			(stroke
				(width 0.1)
				(type default)
			)
			(layer "B.Fab")
		)
		(fp_line
			(start -0.2794 -0.1016)
			(end 0.2794 -0.1016)
			(stroke
				(width 0.1)
				(type default)
			)
			(layer "B.Fab")
		)
		(fp_line
			(start 0.2794 -0.1016)
			(end 0.2794 0.9906)
			(stroke
				(width 0.1)
				(type default)
			)
			(layer "B.Fab")
		)
		(pad "1" smd rect
			(at 0 0 90)
			(size 0.508 0.508)
			(layers "B.Cu" "B.Mask" "B.Paste")
			(net "A_USB2AVRES")
		)
		(pad "2" smd rect
			(at 0 0.889 90)
			(size 0.508 0.508)
			(layers "B.Cu" "B.Mask" "B.Paste")
			(net "GND")
		)
		(zone
			(layer "B.Cu")
			(hatch none 0.5)
			(connect_pads
				(clearance 0)
			)
			(min_thickness 0.25)
			(keepout
				(tracks not_allowed)
				(vias allowed)
				(pads allowed)
				(copperpour not_allowed)
				(footprints allowed)
			)
			(placement
				(enabled no)
				(sheetname "")
			)
			(fill
				(thermal_gap 0.5)
				(thermal_bridge_width 0.5)
				(island_removal_mode 0)
			)
			(polygon
				(pts
					(xy 406.257506 -32.4104) (xy 406.257506 -32.9184) (xy 406.638506 -32.9184) (xy 406.638506 -32.4104)
				)
			)
		)
		(zone
			(layer "B.Cu")
			(hatch none 0.5)
			(connect_pads
				(clearance 0)
			)
			(min_thickness 0.25)
			(keepout
				(tracks allowed)
				(vias not_allowed)
				(pads allowed)
				(copperpour not_allowed)
				(footprints allowed)
			)
			(placement
				(enabled no)
				(sheetname "")
			)
			(fill
				(thermal_gap 0.5)
				(thermal_bridge_width 0.5)
				(island_removal_mode 0)
			)
			(polygon
				(pts
					(xy 406.638506 -32.4104) (xy 406.638506 -32.9184) (xy 406.257506 -32.9184) (xy 406.257506 -32.4104)
				)
			)
		)
	)
)
